# T6G (Grand Teton) — schematic netlist excerpt (pin names and nets, part order shuffled) for the footprints in the layout excerpt that follows; sources: Cadence DE-HDL packaged netlist, KiCad conversion of 04192023_DAF0TMB3IC0_F0TG_MB_C_brd_V02_OCP.brd

R6280  Q_RES  0 5% CHIP  pkg 0402LF  page 179 : A = SMB_USB_CPU0_HUB1_SCL ; B = SMB_USB_HUB2_TI_SCL_MRP_PRT_CTL1

PU6000  MPQ8626GDZ  MPQ8626GD-Z IC  pkg QFN14_0-5_3X2XA  page 269
  PGND1  = GND
  SW1  = SW_P1V8_AUX_PH
  VIN  = SW_P12V_AUX_P1V8_AUX_FLT
  CS  = P1V8_AUX_CS
  EN  = P1V8_AUX_ENABLE
  FB  = P1V8_AUX_FB
  AGND  = GND
  TRK_REF  = P1V8_AUX_REF
  PGOOD  = PWRGD_P1V8_AUX
  BST  = SW_P1V8_AUX_BT
  SW2  = SW_P1V8_AUX_PH
  MODE  = P1V8_AUX_MODE
  VCC  = P1V8_AUX_VCC
  PGND2  = GND

(kicad_pcb
	(version 20260206)
	(generator "pcbnew")
	(generator_version "10.0")
	(general
		(thickness 1.6)
		(legacy_teardrops no)
	)
	(paper "A4")
	(title_block
		(title "04192023_DAF0TMB3IC0_F0TG_MB_C_brd_V02_OCP.brd")
		(comment 1 "Grand Teton / footprints 2528-2529 of 8354")
	)
	(layers
		(0 "F.Cu" signal "TOP")
		(4 "In1.Cu" signal "GND")
		(6 "In2.Cu" signal "IN1")
		(8 "In3.Cu" signal "GND1")
		(10 "In4.Cu" signal "IN2")
		(12 "In5.Cu" signal "GND2")
		(14 "In6.Cu" signal "IN3")
		(16 "In7.Cu" signal "GND3")
		(18 "In8.Cu" signal "VCC")
		(20 "In9.Cu" signal "VCC1")
		(22 "In10.Cu" signal "GND4")
		(24 "In11.Cu" signal "IN4")
		(26 "In12.Cu" signal "GND5")
		(28 "In13.Cu" signal "IN5")
		(30 "In14.Cu" signal "GND6")
		(32 "In15.Cu" signal "IN6")
		(34 "In16.Cu" signal "GND7")
		(2 "B.Cu" signal "BOTTOM")
		(9 "F.Adhes" user "F.Adhesive")
		(11 "B.Adhes" user "B.Adhesive")
		(13 "F.Paste" user "Package Geometry/Pastemask Top")
		(15 "B.Paste" user "Package Geometry/Pastemask Bottom")
		(5 "F.SilkS" user "Ref Des/Silkscreen Top")
		(7 "B.SilkS" user "Ref Des/Silkscreen Bottom")
		(1 "F.Mask" user "Board Geometry/Soldermask Top")
		(3 "B.Mask" user "Board Geometry/Soldermask Bottom")
		(17 "Dwgs.User" user "User.Drawings")
		(19 "Cmts.User" user "User.Comments")
		(21 "Eco1.User" user "User.Eco1")
		(23 "Eco2.User" user "User.Eco2")
		(25 "Edge.Cuts" user "Board Geometry/Outline")
		(27 "Margin" user)
		(31 "F.CrtYd" user "Package Geometry/Place Bound Top")
		(29 "B.CrtYd" user "Package Geometry/Place Bound Bottom")
		(35 "F.Fab" user "Ref Des/Assembly Top")
		(33 "B.Fab" user "Ref Des/Assembly Bottom")
	)
	(footprint ""
		(layer "F.Cu")
		(at 119.379238 -41.17975 -90)
		(property "Reference" "R6280"
			(at 0 0 270)
			(layer "F.SilkS")
			(hide yes)
			(effects
				(font
					(size 1.27 1.27)
				)
			)
		)
		(property "Value" ""
			(at 0 0 270)
			(layer "F.Fab")
			(effects
				(font
					(size 1.27 1.27)
				)
			)
		)
		(duplicate_pad_numbers_are_jumpers no)
		(fp_line
			(start -0.7874 0.4064)
			(end -0.7874 -0.4064)
			(stroke
				(width 0.1524)
				(type default)
			)
			(layer "F.SilkS")
		)
		(fp_line
			(start 0.7874 0.4064)
			(end -0.7874 0.4064)
			(stroke
				(width 0.1524)
				(type default)
			)
			(layer "F.SilkS")
		)
		(fp_line
			(start -0.7874 -0.4064)
			(end 0.7874 -0.4064)
			(stroke
				(width 0.1524)
				(type default)
			)
			(layer "F.SilkS")
		)
		(fp_line
			(start 0.7874 -0.4064)
			(end 0.7874 0.4064)
			(stroke
				(width 0.1524)
				(type default)
			)
			(layer "F.SilkS")
		)
		(fp_line
			(start -0.67945 0.3048)
			(end -0.67945 -0.305054)
			(stroke
				(width 0.1)
				(type default)
			)
			(layer "F.Fab")
		)
		(fp_line
			(start -0.12065 0.3048)
			(end -0.67945 0.3048)
			(stroke
				(width 0.1)
				(type default)
			)
			(layer "F.Fab")
		)
		(fp_line
			(start 0.120396 0.3048)
			(end 0.120396 0.2794)
			(stroke
				(width 0.1)
				(type default)
			)
			(layer "F.Fab")
		)
		(fp_line
			(start 0.67945 0.3048)
			(end 0.120396 0.3048)
			(stroke
				(width 0.1)
				(type default)
			)
			(layer "F.Fab")
		)
		(fp_line
			(start -0.12065 0.2794)
			(end -0.12065 0.3048)
			(stroke
				(width 0.1)
				(type default)
			)
			(layer "F.Fab")
		)
		(fp_line
			(start 0.120396 0.2794)
			(end -0.12065 0.2794)
			(stroke
				(width 0.1)
				(type default)
			)
			(layer "F.Fab")
		)
		(fp_line
			(start -0.12065 -0.2794)
			(end 0.12065 -0.2794)
			(stroke
				(width 0.1)
				(type default)
			)
			(layer "F.Fab")
		)
		(fp_line
			(start 0.12065 -0.2794)
			(end 0.12065 -0.3048)
			(stroke
				(width 0.1)
				(type default)
			)
			(layer "F.Fab")
		)
		(fp_line
			(start 0.12065 -0.3048)
			(end 0.67945 -0.3048)
			(stroke
				(width 0.1)
				(type default)
			)
			(layer "F.Fab")
		)
		(fp_line
			(start 0.67945 -0.3048)
			(end 0.67945 0.3048)
			(stroke
				(width 0.1)
				(type default)
			)
			(layer "F.Fab")
		)
		(fp_line
			(start -0.67945 -0.305054)
			(end -0.12065 -0.305054)
			(stroke
				(width 0.1)
				(type default)
			)
			(layer "F.Fab")
		)
		(fp_line
			(start -0.12065 -0.305054)
			(end -0.12065 -0.2794)
			(stroke
				(width 0.1)
				(type default)
			)
			(layer "F.Fab")
		)
		(pad "1" smd circle
			(at -0.40005 0 270)
			(size 0 0)
			(layers "F.Cu" "F.Mask" "F.Paste")
			(net "SMB_USB_CPU0_HUB1_SCL")
		)
		(pad "2" smd circle
			(at 0.40005 0 270)
			(size 0 0)
			(layers "F.Cu" "F.Mask" "F.Paste")
			(net "SMB_USB_HUB2_TI_SCL_MRP_PRT_CTL1")
		)
	)
	(footprint ""
		(layer "F.Cu")
		(at 143.46174 -78.287626)
		(property "Reference" "PU6000"
			(at -5.757672 -4.30784 0)
			(unlocked yes)
			(layer "F.SilkS")
			(effects
				(font
					(size 0.7874 0.5842)
					(thickness 0.1524)
				)
				(justify left)
			)
		)
		(property "Value" ""
			(at 0 0 0)
			(layer "F.Fab")
			(effects
				(font
					(size 1.27 1.27)
				)
			)
		)
		(duplicate_pad_numbers_are_jumpers no)
		(fp_line
			(start -1.050036 -1.549908)
			(end -0.503936 -1.549908)
			(stroke
				(width 0.1524)
				(type default)
			)
			(layer "F.SilkS")
		)
		(fp_line
			(start -1.050036 -1.253998)
			(end -1.050036 -1.549908)
			(stroke
				(width 0.1524)
				(type default)
			)
			(layer "F.SilkS")
		)
		(fp_line
			(start -1.050036 1.549908)
			(end -1.050036 1.253998)
			(stroke
				(width 0.1524)
				(type default)
			)
			(layer "F.SilkS")
		)
		(fp_line
			(start -0.503936 1.549908)
			(end -1.050036 1.549908)
			(stroke
				(width 0.1524)
				(type default)
			)
			(layer "F.SilkS")
		)
		(fp_line
			(start 0.503936 -1.549908)
			(end 1.050036 -1.549908)
			(stroke
				(width 0.1524)
				(type default)
			)
			(layer "F.SilkS")
		)
		(fp_line
			(start 1.050036 -1.549908)
			(end 1.050036 -1.253998)
			(stroke
				(width 0.1524)
				(type default)
			)
			(layer "F.SilkS")
		)
		(fp_line
			(start 1.050036 1.253998)
			(end 1.050036 1.549908)
			(stroke
				(width 0.1524)
				(type default)
			)
			(layer "F.SilkS")
		)
		(fp_line
			(start 1.050036 1.549908)
			(end 0.503936 1.549908)
			(stroke
				(width 0.1524)
				(type default)
			)
			(layer "F.SilkS")
		)
		(fp_poly
			(pts
				(xy -1.499616 -1.491488) (xy -2.307844 -1.760982) (xy -1.76911 -2.299716)
			)
			(stroke
				(width 0)
				(type default)
			)
			(fill yes)
			(layer "F.SilkS")
		)
		(fp_line
			(start -1.050036 -1.549908)
			(end 1.050036 -1.549908)
			(stroke
				(width 0.1)
				(type default)
			)
			(layer "F.Fab")
		)
		(fp_line
			(start -1.050036 1.549908)
			(end -1.050036 -1.549908)
			(stroke
				(width 0.1)
				(type default)
			)
			(layer "F.Fab")
		)
		(fp_line
			(start 1.050036 -1.549908)
			(end 1.050036 1.549908)
			(stroke
				(width 0.1)
				(type default)
			)
			(layer "F.Fab")
		)
		(fp_line
			(start 1.050036 1.549908)
			(end -1.050036 1.549908)
			(stroke
				(width 0.1)
				(type default)
			)
			(layer "F.Fab")
		)
		(fp_poly
			(pts
				(xy -2.2352 -0.618998) (xy -2.2352 -1.380998) (xy -1.4732 -0.999998)
			)
			(stroke
				(width 0)
				(type default)
			)
			(fill yes)
			(layer "F.Fab")
		)
		(pad "1" smd circle
			(at -0.94996 -0.999998 270)
			(size 0 0)
			(layers "F.Cu" "F.Mask" "F.Paste")
			(net "GND")
		)
		(pad "2" smd rect
			(at -0.849884 -0.499872 90)
			(size 0.254 0.9144)
			(layers "F.Cu" "F.Mask" "F.Paste")
			(net "SW_P1V8_AUX_PH")
		)
		(pad "3" smd rect
			(at -0.649986 0 90)
			(size 0.254 1.3208)
			(layers "F.Cu" "F.Mask" "F.Paste")
			(net "SW_P12V_AUX_P1V8_AUX_FLT")
		)
		(pad "4" smd rect
			(at -0.849884 0.499872 90)
			(size 0.254 0.9144)
			(layers "F.Cu" "F.Mask" "F.Paste")
			(net "P1V8_AUX_CS")
		)
		(pad "5" smd circle
			(at -0.94996 0.999998 270)
			(size 0 0)
			(layers "F.Cu" "F.Mask" "F.Paste")
			(net "P1V8_AUX_ENABLE")
		)
		(pad "6" smd circle
			(at -0.249936 1.450086)
			(size 0 0)
			(layers "F.Cu" "F.Mask" "F.Paste")
			(net "P1V8_AUX_FB")
		)
		(pad "7" smd circle
			(at 0.249936 1.450086)
			(size 0 0)
			(layers "F.Cu" "F.Mask" "F.Paste")
			(net "GND")
		)
		(pad "8" smd circle
			(at 0.94996 0.999998 90)
			(size 0 0)
			(layers "F.Cu" "F.Mask" "F.Paste")
			(net "P1V8_AUX_REF")
		)
		(pad "9" smd rect
			(at 0.849884 0.499872 90)
			(size 0.254 0.9144)
			(layers "F.Cu" "F.Mask" "F.Paste")
			(net "PWRGD_P1V8_AUX")
		)
		(pad "10" smd rect
			(at 0.849884 0 90)
			(size 0.254 0.9144)
			(layers "F.Cu" "F.Mask" "F.Paste")
			(net "SW_P1V8_AUX_BT")
		)
		(pad "11" smd rect
			(at 0.849884 -0.499872 90)
			(size 0.254 0.9144)
			(layers "F.Cu" "F.Mask" "F.Paste")
			(net "SW_P1V8_AUX_PH")
		)
		(pad "12" smd circle
			(at 0.94996 -0.999998 90)
			(size 0 0)
			(layers "F.Cu" "F.Mask" "F.Paste")
			(net "P1V8_AUX_MODE")
		)
		(pad "13" smd circle
			(at 0.249936 -1.450086 180)
			(size 0 0)
			(layers "F.Cu" "F.Mask" "F.Paste")
			(net "P1V8_AUX_VCC")
		)
		(pad "14" smd circle
			(at -0.249936 -1.450086 180)
			(size 0 0)
			(layers "F.Cu" "F.Mask" "F.Paste")
			(net "GND")
		)
	)
)
